# T6G (Grand Teton) — schematic netlist excerpt (pin names and nets, part order shuffled) for the footprints in the layout excerpt that follows; sources: Cadence DE-HDL packaged netlist, KiCad conversion of 04192023_DAF0TMB3IC0_F0TG_MB_C_brd_V02_OCP.brd

J15  SCONN288_DDR506112002KQ  IO  pkg DDR288S_1-1VXC  page 87
  VIN_BULK0  = P12V_MEM_CPU0
  RFU0  = NC
  VIN_MGMT  = P3V3_AUX
  HSCL  = I3C_SPD_DDRB_CPU0_SCL
  HSDA  = I3C_SPD_DDRB_CPU0_SDA
  VSS0  = GND
  DQ0_A  = M_B_CPU0_SA_DQ<0>
  VSS1  = GND
  DQ1_A  = M_B_CPU0_SA_DQ<1>
  VSS2  = GND
  DQS0_A_T  = M_B_CPU0_SA_DQS_DP<0>
  DQS0_A_C  = M_B_CPU0_SA_DQS_DN<0>
  VSS3  = GND
  DQ4_A  = M_B_CPU0_SA_DQ<4>
  VSS4  = GND
  DQ5_A  = M_B_CPU0_SA_DQ<5>
  VSS5  = GND
  DQ8_A  = M_B_CPU0_SA_DQ<8>
  VSS6  = GND
  DQ9_A  = M_B_CPU0_SA_DQ<9>
  VSS7  = GND
  DQS1_A_T  = M_B_CPU0_SA_DQS_DP<1>
  DQS1_A_C  = M_B_CPU0_SA_DQS_DN<1>
  VSS8  = GND
  DQ12_A  = M_B_CPU0_SA_DQ<12>
  VSS9  = GND
  DQ13_A  = M_B_CPU0_SA_DQ<13>
  VSS10  = GND
  DQ16_A  = M_B_CPU0_SA_DQ<16>
  VSS11  = GND
  DQ17_A  = M_B_CPU0_SA_DQ<17>
  VSS12  = GND
  DQS2_A_T  = M_B_CPU0_SA_DQS_DP<2>
  DQS2_A_C  = M_B_CPU0_SA_DQS_DN<2>
  VSS13  = GND
  DQ20_A  = M_B_CPU0_SA_DQ<20>
  VSS14  = GND
  DQ21_A  = M_B_CPU0_SA_DQ<21>
  VSS15  = GND
  DQ24_A  = M_B_CPU0_SA_DQ<24>
  VSS16  = GND
  DQ25_A  = M_B_CPU0_SA_DQ<25>
  VSS17  = GND
  DQS3_A_T  = M_B_CPU0_SA_DQS_DP<3>
  DQS3_A_C  = M_B_CPU0_SA_DQS_DN<3>
  VSS18  = GND
  DQ28_A  = M_B_CPU0_SA_DQ<28>
  VSS19  = GND
  DQ29_A  = M_B_CPU0_SA_DQ<29>
  VSS20  = GND
  CB0_A  = M_B_CPU0_SA_CB<0>
  VSS21  = GND
  CB1_A  = M_B_CPU0_SA_CB<1>
  VSS22  = GND
  DQS4_A_T  = M_B_CPU0_SA_DQS_DP<4>
  DQS4_A_C  = M_B_CPU0_SA_DQS_DN<4>
  VSS23  = GND
  CB4_A  = M_B_CPU0_SA_CB<4>
  VSS24  = GND
  CB5_A  = M_B_CPU0_SA_CB<5>
  VSS25  = GND
  ALERT_N  = M_B_CPU0_ALERT_N
  VSS26  = GND
  CS0_A_N  = M_B_CPU0_SA_CS_N<0>
  VSS27  = GND
  CA0_A  = M_B_CPU0_SA_CA<0>
  VSS28  = GND
  CA2_A  = M_B_CPU0_SA_CA<2>
  VSS29  = GND
  CA4_A  = M_B_CPU0_SA_CA<4>
  VSS30  = GND
  CA6_A  = M_B_CPU0_SA_CA<6>
  VSS31  = GND
  PAR_A  = M_B_CPU0_SA_PAR
  VSS32  = GND
  CA0_B  = M_B_CPU0_SB_CA<0>
  VSS33  = GND
  CA2_B  = M_B_CPU0_SB_CA<2>
  VSS34  = GND
  CA4_B  = M_B_CPU0_SB_CA<4>
  VSS35  = GND
  CA6_B  = M_B_CPU0_SB_CA<6>
  VSS36  = GND
  CS0_B_N  = M_B_CPU0_SB_CS_N<0>
  VSS37  = GND
  \lbd||rsp_a_n\  = M_B_CPU0_SA_RSP<0>
  \lbs||rsp_b_n\  = M_B_CPU0_SB_RSP<0>
  VSS38  = GND
  CB4_B  = M_B_CPU0_SB_CB<4>
  VSS39  = GND
  CB5_B  = M_B_CPU0_SB_CB<5>
  VSS40  = GND
  \dqs9_b_t||tdqs9_b_t||dbi4_b_n\  = M_B_CPU0_SB_DQS_DP<9>
  \dqs9_b_c||tdqs9_b_c\  = M_B_CPU0_SB_DQS_DN<9>
  VSS41  = GND
  CB0_B  = M_B_CPU0_SB_CB<0>
  VSS42  = GND
  CB1_B  = M_B_CPU0_SB_CB<1>
  VSS43  = GND
  DQ0_B  = M_B_CPU0_SB_DQ<0>
  VSS44  = GND
  DQ1_B  = M_B_CPU0_SB_DQ<1>
  VSS45  = GND
  DQS0_B_T  = M_B_CPU0_SB_DQS_DP<0>
  DQS0_B_C  = M_B_CPU0_SB_DQS_DN<0>
  VSS46  = GND
  DQ4_B  = M_B_CPU0_SB_DQ<4>
  VSS47  = GND
  DQ5_B  = M_B_CPU0_SB_DQ<5>
  VSS48  = GND
  DQ8_B  = M_B_CPU0_SB_DQ<8>
  VSS49  = GND
  DQ9_B  = M_B_CPU0_SB_DQ<9>
  VSS50  = GND
  DQS1_B_T  = M_B_CPU0_SB_DQS_DP<1>
  DQS1_B_C  = M_B_CPU0_SB_DQS_DN<1>
  VSS51  = GND
  DQ12_B  = M_B_CPU0_SB_DQ<12>
  VSS52  = GND
  DQ13_B  = M_B_CPU0_SB_DQ<13>
  VSS53  = GND
  DQ16_B  = M_B_CPU0_SB_DQ<16>
  VSS54  = GND
  DQ17_B  = M_B_CPU0_SB_DQ<17>
  VSS55  = GND
  DQS2_B_T  = M_B_CPU0_SB_DQS_DP<2>
  DQS2_B_C  = M_B_CPU0_SB_DQS_DN<2>
  VSS56  = GND
  DQ20_B  = M_B_CPU0_SB_DQ<20>
  VSS57  = GND
  DQ21_B  = M_B_CPU0_SB_DQ<21>
  VSS58  = GND
  DQ24_B  = M_B_CPU0_SB_DQ<24>
  VSS59  = GND
  DQ25_B  = M_B_CPU0_SB_DQ<25>
  VSS60  = GND
  DQS3_B_T  = M_B_CPU0_SB_DQS_DP<3>
  DQS3_B_C  = M_B_CPU0_SB_DQS_DN<3>
  VSS61  = GND
  DQ28_B  = M_B_CPU0_SB_DQ<28>
  VSS62  = GND
  DQ29_B  = M_B_CPU0_SB_DQ<29>
  VSS63  = GND
  RFU1  = NC
  VIN_BULK1  = P12V_MEM_CPU0
  VIN_BULK2  = P12V_MEM_CPU0
  \pwr_good||fail_n\  = PWRGD_CHB_CPU0_DIMM
  HAS  = PD_CHB_CPU0_DIMM_SAA
  RFU2  = NC
  RFU3  = NC
  VSS64  = GND
  DQ2_A  = M_B_CPU0_SA_DQ<2>
  VSS65  = GND
  DQ3_A  = M_B_CPU0_SA_DQ<3>
  VSS66  = GND
  \dqs5_a_c||tdqs5_a_c||dqs5_a_t||tdqs5_a_t\  = M_B_CPU0_SA_DQS_DN<5>
  \dqs5_a_t||tdqs5_a_t\  = M_B_CPU0_SA_DQS_DP<5>
  VSS67  = GND
  DQ6_A  = M_B_CPU0_SA_DQ<6>
  VSS68  = GND
  DQ7_A  = M_B_CPU0_SA_DQ<7>
  VSS69  = GND
  DQ10_A  = M_B_CPU0_SA_DQ<10>
  VSS70  = GND
  DQ11_A  = M_B_CPU0_SA_DQ<11>
  VSS71  = GND
  \dqs6_a_c||tdqs6_a_c||dqs6_a_t||tdqs6_a_t\  = M_B_CPU0_SA_DQS_DN<6>
  \dqs6_a_t||tdqs6_a_t\  = M_B_CPU0_SA_DQS_DP<6>
  VSS72  = GND
  DQ14_A  = M_B_CPU0_SA_DQ<14>
  VSS73  = GND
  DQ15_A  = M_B_CPU0_SA_DQ<15>
  VSS74  = GND
  DQ18_A  = M_B_CPU0_SA_DQ<18>
  VSS75  = GND
  DQ19_A  = M_B_CPU0_SA_DQ<19>
  VSS76  = GND
  \dqs7_a_c||tdqs7_a_c\  = M_B_CPU0_SA_DQS_DN<7>
  \dqs7_a_t||tdqs7_a_t\  = M_B_CPU0_SA_DQS_DP<7>
  VSS77  = GND
  DQ22_A  = M_B_CPU0_SA_DQ<22>
  VSS78  = GND
  DQ23_A  = M_B_CPU0_SA_DQ<23>
  VSS79  = GND
  DQ26_A  = M_B_CPU0_SA_DQ<26>
  VSS80  = GND
  DQ27_A  = M_B_CPU0_SA_DQ<27>
  VSS81  = GND
  \dqs8_a_c||tdqs8_a_c\  = M_B_CPU0_SA_DQS_DN<8>
  \dqs8_a_t||tdqs8_a_t\  = M_B_CPU0_SA_DQS_DP<8>
  VSS82  = GND
  DQ30_A  = M_B_CPU0_SA_DQ<30>
  VSS83  = GND
  DQ31_A  = M_B_CPU0_SA_DQ<31>
  VSS84  = GND
  CB2_A  = M_B_CPU0_SA_CB<2>
  VSS85  = GND
  CB3_A  = M_B_CPU0_SA_CB<3>
  VSS86  = GND
  \dqs9_a_c||tdqs9_a_c\  = M_B_CPU0_SA_DQS_DN<9>
  \dqs9_a_t||tdqs9_a_t\  = M_B_CPU0_SA_DQS_DP<9>
  VSS87  = GND
  CB6_A  = M_B_CPU0_SA_CB<6>
  VSS88  = GND
  CB7_A  = M_B_CPU0_SA_CB<7>
  VSS89  = GND
  RESET_N  = M_B_CPU0_RESET_N
  VSS90  = GND
  CS1_A_N  = M_B_CPU0_SA_CS_N<1>
  VSS91  = GND
  CA1_A  = M_B_CPU0_SA_CA<1>
  VSS92  = GND
  CA3_A  = M_B_CPU0_SA_CA<3>
  VSS93  = GND
  CA5_A  = M_B_CPU0_SA_CA<5>
  VSS94  = GND
  CK_T  = M_B_CPU0_CLK_DP<0>
  CK_C  = M_B_CPU0_CLK_DN<0>
  VSS95  = GND
  RFU4  = NC
  CA1_B  = M_B_CPU0_SB_CA<1>
  VSS96  = GND
  CA3_B  = M_B_CPU0_SB_CA<3>
  VSS97  = GND
  CA5_B  = M_B_CPU0_SB_CA<5>
  VSS98  = GND
  PAR_B  = M_B_CPU0_SB_PAR
  VSS99  = GND
  CS1_B_N  = M_B_CPU0_SB_CS_N<1>
  VSS100  = GND
  RFU5  = NC
  RFU6  = NC
  VSS101  = GND
  CB6_B  = M_B_CPU0_SB_CB<6>
  VSS102  = GND
  CB7_B  = M_B_CPU0_SB_CB<7>
  VSS103  = GND
  DQS4_B_C  = M_B_CPU0_SB_DQS_DN<4>
  DQS4_B_T  = M_B_CPU0_SB_DQS_DP<4>
  VSS104  = GND
  CB2_B  = M_B_CPU0_SB_CB<2>
  VSS105  = GND
  CB3_B  = M_B_CPU0_SB_CB<3>
  VSS106  = GND
  DQ2_B  = M_B_CPU0_SB_DQ<2>
  VSS107  = GND
  DQ3_B  = M_B_CPU0_SB_DQ<3>
  VSS108  = GND
  \dqs5_b_c||tdqs5_b_c\  = M_B_CPU0_SB_DQS_DN<5>
  \dqs5_b_t||tdqs5_b_t\  = M_B_CPU0_SB_DQS_DP<5>
  VSS109  = GND
  DQ6_B  = M_B_CPU0_SB_DQ<6>
  VSS110  = GND
  DQ7_B  = M_B_CPU0_SB_DQ<7>
  VSS111  = GND
  DQ10_B  = M_B_CPU0_SB_DQ<10>
  VSS112  = GND
  DQ11_B  = M_B_CPU0_SB_DQ<11>
  VSS113  = GND
  \dqs6_b_c||tdqs6_b_c\  = M_B_CPU0_SB_DQS_DN<6>
  \dqs6_b_t||tdqs6_b_t\  = M_B_CPU0_SB_DQS_DP<6>
  VSS114  = GND
  DQ14_B  = M_B_CPU0_SB_DQ<14>
  VSS115  = GND
  DQ15_B  = M_B_CPU0_SB_DQ<15>
  VSS116  = GND
  DQ18_B  = M_B_CPU0_SB_DQ<18>
  VSS117  = GND
  DQ19_B  = M_B_CPU0_SB_DQ<19>
  VSS118  = GND
  \dqs7_b_c||tdqs7_b_c\  = M_B_CPU0_SB_DQS_DN<7>
  \dqs7_b_t||tdqs7_b_t\  = M_B_CPU0_SB_DQS_DP<7>
  VSS119  = GND
  DQ22_B  = M_B_CPU0_SB_DQ<22>
  VSS120  = GND
  DQ23_B  = M_B_CPU0_SB_DQ<23>
  VSS121  = GND
  DQ26_B  = M_B_CPU0_SB_DQ<26>
  VSS122  = GND
  DQ27_B  = M_B_CPU0_SB_DQ<27>
  VSS123  = GND
  \dqs8_b_c||tdqs8_b_c\  = M_B_CPU0_SB_DQS_DN<8>
  \dqs8_b_t||tdqs8_b_t\  = M_B_CPU0_SB_DQS_DP<8>
  VSS124  = GND
  DQ30_B  = M_B_CPU0_SB_DQ<30>
  VSS125  = GND
  DQ31_B  = M_B_CPU0_SB_DQ<31>
  VSS126  = GND
  G1  = GND
  G2  = GND
  G3  = GND

(kicad_pcb
	(version 20260206)
	(generator "pcbnew")
	(generator_version "10.0")
	(general
		(thickness 1.6)
		(legacy_teardrops no)
	)
	(paper "A4")
	(title_block
		(title "04192023_DAF0TMB3IC0_F0TG_MB_C_brd_V02_OCP.brd")
		(comment 1 "Grand Teton / footprint 1120 of 8354 (J15), pads 185-230 of 291")
	)
	(layers
		(0 "F.Cu" signal "TOP")
		(4 "In1.Cu" signal "GND")
		(6 "In2.Cu" signal "IN1")
		(8 "In3.Cu" signal "GND1")
		(10 "In4.Cu" signal "IN2")
		(12 "In5.Cu" signal "GND2")
		(14 "In6.Cu" signal "IN3")
		(16 "In7.Cu" signal "GND3")
		(18 "In8.Cu" signal "VCC")
		(20 "In9.Cu" signal "VCC1")
		(22 "In10.Cu" signal "GND4")
		(24 "In11.Cu" signal "IN4")
		(26 "In12.Cu" signal "GND5")
		(28 "In13.Cu" signal "IN5")
		(30 "In14.Cu" signal "GND6")
		(32 "In15.Cu" signal "IN6")
		(34 "In16.Cu" signal "GND7")
		(2 "B.Cu" signal "BOTTOM")
		(9 "F.Adhes" user "F.Adhesive")
		(11 "B.Adhes" user "B.Adhesive")
		(13 "F.Paste" user "Package Geometry/Pastemask Top")
		(15 "B.Paste" user "Package Geometry/Pastemask Bottom")
		(5 "F.SilkS" user "Ref Des/Silkscreen Top")
		(7 "B.SilkS" user "Ref Des/Silkscreen Bottom")
		(1 "F.Mask" user "Board Geometry/Soldermask Top")
		(3 "B.Mask" user "Board Geometry/Soldermask Bottom")
		(17 "Dwgs.User" user "User.Drawings")
		(19 "Cmts.User" user "User.Comments")
		(21 "Eco1.User" user "User.Eco1")
		(23 "Eco2.User" user "User.Eco2")
		(25 "Edge.Cuts" user "Board Geometry/Outline")
		(27 "Margin" user)
		(31 "F.CrtYd" user "Package Geometry/Place Bound Top")
		(29 "B.CrtYd" user "Package Geometry/Place Bound Bottom")
		(35 "F.Fab" user "Ref Des/Assembly Top")
		(33 "B.Fab" user "Ref Des/Assembly Bottom")
	)
	(footprint ""
		(layer "F.Cu")
		(at 297.774106 -255.560068 180)
		(property "Reference" "J15"
			(at -2.2098 -81.984088 0)
			(unlocked yes)
			(layer "F.SilkS")
			(effects
				(font
					(size 0.7874 0.5842)
					(thickness 0.1524)
				)
			)
		)
		(property "Value" ""
			(at 0 0 180)
			(layer "F.Fab")
			(effects
				(font
					(size 1.27 1.27)
				)
			)
		)
		(duplicate_pad_numbers_are_jumpers no)
		(pad "185" smd rect
			(at 2.050034 -29.325062 90)
			(size 0.519938 1.4986)
			(layers "F.Cu" "F.Mask" "F.Paste")
			(net "M_B_CPU0_SA_DQ<26>")
		)
		(pad "186" smd rect
			(at 2.050034 -28.474924 90)
			(size 0.519938 1.4986)
			(layers "F.Cu" "F.Mask" "F.Paste")
			(net "GND")
		)
		(pad "187" smd rect
			(at 2.050034 -27.62504 90)
			(size 0.519938 1.4986)
			(layers "F.Cu" "F.Mask" "F.Paste")
			(net "M_B_CPU0_SA_DQ<27>")
		)
		(pad "188" smd rect
			(at 2.050034 -26.774902 90)
			(size 0.519938 1.4986)
			(layers "F.Cu" "F.Mask" "F.Paste")
			(net "GND")
		)
		(pad "189" smd rect
			(at 2.050034 -25.925018 90)
			(size 0.519938 1.4986)
			(layers "F.Cu" "F.Mask" "F.Paste")
			(net "M_B_CPU0_SA_DQS_DN<8>")
		)
		(pad "190" smd rect
			(at 2.050034 -25.07488 90)
			(size 0.519938 1.4986)
			(layers "F.Cu" "F.Mask" "F.Paste")
			(net "M_B_CPU0_SA_DQS_DP<8>")
		)
		(pad "191" smd rect
			(at 2.050034 -24.224996 90)
			(size 0.519938 1.4986)
			(layers "F.Cu" "F.Mask" "F.Paste")
			(net "GND")
		)
		(pad "192" smd rect
			(at 2.050034 -23.375112 90)
			(size 0.519938 1.4986)
			(layers "F.Cu" "F.Mask" "F.Paste")
			(net "M_B_CPU0_SA_DQ<30>")
		)
		(pad "193" smd rect
			(at 2.050034 -22.524974 90)
			(size 0.519938 1.4986)
			(layers "F.Cu" "F.Mask" "F.Paste")
			(net "GND")
		)
		(pad "194" smd rect
			(at 2.050034 -21.67509 90)
			(size 0.519938 1.4986)
			(layers "F.Cu" "F.Mask" "F.Paste")
			(net "M_B_CPU0_SA_DQ<31>")
		)
		(pad "195" smd rect
			(at 2.050034 -20.824952 90)
			(size 0.519938 1.4986)
			(layers "F.Cu" "F.Mask" "F.Paste")
			(net "GND")
		)
		(pad "196" smd rect
			(at 2.050034 -19.975068 90)
			(size 0.519938 1.4986)
			(layers "F.Cu" "F.Mask" "F.Paste")
			(net "M_B_CPU0_SA_CB<2>")
		)
		(pad "197" smd rect
			(at 2.050034 -19.12493 90)
			(size 0.519938 1.4986)
			(layers "F.Cu" "F.Mask" "F.Paste")
			(net "GND")
		)
		(pad "198" smd rect
			(at 2.050034 -18.275046 90)
			(size 0.519938 1.4986)
			(layers "F.Cu" "F.Mask" "F.Paste")
			(net "M_B_CPU0_SA_CB<3>")
		)
		(pad "199" smd rect
			(at 2.050034 -17.424908 90)
			(size 0.519938 1.4986)
			(layers "F.Cu" "F.Mask" "F.Paste")
			(net "GND")
		)
		(pad "200" smd rect
			(at 2.050034 -16.575024 90)
			(size 0.519938 1.4986)
			(layers "F.Cu" "F.Mask" "F.Paste")
			(net "M_B_CPU0_SA_DQS_DN<9>")
		)
		(pad "201" smd rect
			(at 2.050034 -15.724886 90)
			(size 0.519938 1.4986)
			(layers "F.Cu" "F.Mask" "F.Paste")
			(net "M_B_CPU0_SA_DQS_DP<9>")
		)
		(pad "202" smd rect
			(at 2.050034 -14.875002 90)
			(size 0.519938 1.4986)
			(layers "F.Cu" "F.Mask" "F.Paste")
			(net "GND")
		)
		(pad "203" smd rect
			(at 2.050034 -14.025118 90)
			(size 0.519938 1.4986)
			(layers "F.Cu" "F.Mask" "F.Paste")
			(net "M_B_CPU0_SA_CB<6>")
		)
		(pad "204" smd rect
			(at 2.050034 -13.17498 90)
			(size 0.519938 1.4986)
			(layers "F.Cu" "F.Mask" "F.Paste")
			(net "GND")
		)
		(pad "205" smd rect
			(at 2.050034 -12.325096 90)
			(size 0.519938 1.4986)
			(layers "F.Cu" "F.Mask" "F.Paste")
			(net "M_B_CPU0_SA_CB<7>")
		)
		(pad "206" smd rect
			(at 2.050034 -11.474958 90)
			(size 0.519938 1.4986)
			(layers "F.Cu" "F.Mask" "F.Paste")
			(net "GND")
		)
		(pad "207" smd rect
			(at 2.050034 -10.625074 90)
			(size 0.519938 1.4986)
			(layers "F.Cu" "F.Mask" "F.Paste")
			(net "M_B_CPU0_RESET_N")
		)
		(pad "208" smd rect
			(at 2.050034 -9.774936 90)
			(size 0.519938 1.4986)
			(layers "F.Cu" "F.Mask" "F.Paste")
			(net "GND")
		)
		(pad "209" smd rect
			(at 2.050034 -8.925052 90)
			(size 0.519938 1.4986)
			(layers "F.Cu" "F.Mask" "F.Paste")
			(net "M_B_CPU0_SA_CS_N<1>")
		)
		(pad "210" smd rect
			(at 2.050034 -8.074914 90)
			(size 0.519938 1.4986)
			(layers "F.Cu" "F.Mask" "F.Paste")
			(net "GND")
		)
		(pad "211" smd rect
			(at 2.050034 -7.22503 90)
			(size 0.519938 1.4986)
			(layers "F.Cu" "F.Mask" "F.Paste")
			(net "M_B_CPU0_SA_CA<1>")
		)
		(pad "212" smd rect
			(at 2.050034 -6.374892 90)
			(size 0.519938 1.4986)
			(layers "F.Cu" "F.Mask" "F.Paste")
			(net "GND")
		)
		(pad "213" smd rect
			(at 2.050034 -5.525008 90)
			(size 0.519938 1.4986)
			(layers "F.Cu" "F.Mask" "F.Paste")
			(net "M_B_CPU0_SA_CA<3>")
		)
		(pad "214" smd rect
			(at 2.050034 -4.675124 90)
			(size 0.519938 1.4986)
			(layers "F.Cu" "F.Mask" "F.Paste")
			(net "GND")
		)
		(pad "215" smd rect
			(at 2.050034 -3.824986 90)
			(size 0.519938 1.4986)
			(layers "F.Cu" "F.Mask" "F.Paste")
			(net "M_B_CPU0_SA_CA<5>")
		)
		(pad "216" smd rect
			(at 2.050034 -2.975102 90)
			(size 0.519938 1.4986)
			(layers "F.Cu" "F.Mask" "F.Paste")
			(net "GND")
		)
		(pad "217" smd rect
			(at 2.050034 -2.124964 90)
			(size 0.519938 1.4986)
			(layers "F.Cu" "F.Mask" "F.Paste")
			(net "M_B_CPU0_CLK_DP<0>")
		)
		(pad "218" smd rect
			(at 2.050034 -1.27508 90)
			(size 0.519938 1.4986)
			(layers "F.Cu" "F.Mask" "F.Paste")
			(net "M_B_CPU0_CLK_DN<0>")
		)
		(pad "219" smd rect
			(at 2.050034 -0.424942 90)
			(size 0.519938 1.4986)
			(layers "F.Cu" "F.Mask" "F.Paste")
			(net "GND")
		)
		(pad "220" smd rect
			(at 2.050034 5.525008 90)
			(size 0.519938 1.4986)
			(layers "F.Cu" "F.Mask" "F.Paste")
			(net "Net_2267")
		)
		(pad "221" smd rect
			(at 2.050034 6.374892 90)
			(size 0.519938 1.4986)
			(layers "F.Cu" "F.Mask" "F.Paste")
			(net "M_B_CPU0_SB_CA<1>")
		)
		(pad "222" smd rect
			(at 2.050034 7.22503 90)
			(size 0.519938 1.4986)
			(layers "F.Cu" "F.Mask" "F.Paste")
			(net "GND")
		)
		(pad "223" smd rect
			(at 2.050034 8.074914 90)
			(size 0.519938 1.4986)
			(layers "F.Cu" "F.Mask" "F.Paste")
			(net "M_B_CPU0_SB_CA<3>")
		)
		(pad "224" smd rect
			(at 2.050034 8.925052 90)
			(size 0.519938 1.4986)
			(layers "F.Cu" "F.Mask" "F.Paste")
			(net "GND")
		)
		(pad "225" smd rect
			(at 2.050034 9.774936 90)
			(size 0.519938 1.4986)
			(layers "F.Cu" "F.Mask" "F.Paste")
			(net "M_B_CPU0_SB_CA<5>")
		)
		(pad "226" smd rect
			(at 2.050034 10.625074 90)
			(size 0.519938 1.4986)
			(layers "F.Cu" "F.Mask" "F.Paste")
			(net "GND")
		)
		(pad "227" smd rect
			(at 2.050034 11.474958 90)
			(size 0.519938 1.4986)
			(layers "F.Cu" "F.Mask" "F.Paste")
			(net "M_B_CPU0_SB_PAR")
		)
		(pad "228" smd rect
			(at 2.050034 12.325096 90)
			(size 0.519938 1.4986)
			(layers "F.Cu" "F.Mask" "F.Paste")
			(net "GND")
		)
		(pad "229" smd rect
			(at 2.050034 13.17498 90)
			(size 0.519938 1.4986)
			(layers "F.Cu" "F.Mask" "F.Paste")
			(net "M_B_CPU0_SB_CS_N<1>")
		)
		(pad "230" smd rect
			(at 2.050034 14.025118 90)
			(size 0.519938 1.4986)
			(layers "F.Cu" "F.Mask" "F.Paste")
			(net "GND")
		)
	)
)
